# T6G (Grand Teton) — schematic netlist excerpt (pin names and nets, part order shuffled) for the footprints in the layout excerpt that follows; sources: Cadence DE-HDL packaged netlist, KiCad conversion of 04192023_DAF0TMB3IC0_F0TG_MB_C_brd_V02_OCP.brd

C823  Q_CAP_DIFFBUS  DIFF BUS_0.22UF 6.3V 20% X6S  pkg C0201  page 65 : \1\ = P5E_CPU1_P0_TX_C_DP<7> ; \2\ = P5E_CPU1_P0_TX_DP<7>
PC2241  Q_CAP  0.1UF 25V 10% X7R  pkg 0402  page 152 : A = P12V_SCM_R ; B = GND
R3561  Q_RES  0 5% CHIP  pkg 0402LF  page 237 : A = P12V_SCM_ADC_ALERT_R ; B = P12V_SCM_ADC_ALERT

(kicad_pcb
	(version 20260206)
	(generator "pcbnew")
	(generator_version "10.0")
	(general
		(thickness 1.6)
		(legacy_teardrops no)
	)
	(paper "A4")
	(title_block
		(title "04192023_DAF0TMB3IC0_F0TG_MB_C_brd_V02_OCP.brd")
		(comment 1 "Grand Teton / footprints 3561-3563 of 8354")
	)
	(layers
		(0 "F.Cu" signal "TOP")
		(4 "In1.Cu" signal "GND")
		(6 "In2.Cu" signal "IN1")
		(8 "In3.Cu" signal "GND1")
		(10 "In4.Cu" signal "IN2")
		(12 "In5.Cu" signal "GND2")
		(14 "In6.Cu" signal "IN3")
		(16 "In7.Cu" signal "GND3")
		(18 "In8.Cu" signal "VCC")
		(20 "In9.Cu" signal "VCC1")
		(22 "In10.Cu" signal "GND4")
		(24 "In11.Cu" signal "IN4")
		(26 "In12.Cu" signal "GND5")
		(28 "In13.Cu" signal "IN5")
		(30 "In14.Cu" signal "GND6")
		(32 "In15.Cu" signal "IN6")
		(34 "In16.Cu" signal "GND7")
		(2 "B.Cu" signal "BOTTOM")
		(9 "F.Adhes" user "F.Adhesive")
		(11 "B.Adhes" user "B.Adhesive")
		(13 "F.Paste" user "Package Geometry/Pastemask Top")
		(15 "B.Paste" user "Package Geometry/Pastemask Bottom")
		(5 "F.SilkS" user "Ref Des/Silkscreen Top")
		(7 "B.SilkS" user "Ref Des/Silkscreen Bottom")
		(1 "F.Mask" user "Board Geometry/Soldermask Top")
		(3 "B.Mask" user "Board Geometry/Soldermask Bottom")
		(17 "Dwgs.User" user "User.Drawings")
		(19 "Cmts.User" user "User.Comments")
		(21 "Eco1.User" user "User.Eco1")
		(23 "Eco2.User" user "User.Eco2")
		(25 "Edge.Cuts" user "Board Geometry/Outline")
		(27 "Margin" user)
		(31 "F.CrtYd" user "Package Geometry/Place Bound Top")
		(29 "B.CrtYd" user "Package Geometry/Place Bound Bottom")
		(35 "F.Fab" user "Ref Des/Assembly Top")
		(33 "B.Fab" user "Ref Des/Assembly Bottom")
	)
	(footprint ""
		(layer "F.Cu")
		(at 212.118956 -30.276292 -90)
		(property "Reference" "R3561"
			(at 0 0 270)
			(layer "F.SilkS")
			(hide yes)
			(effects
				(font
					(size 1.27 1.27)
				)
			)
		)
		(property "Value" ""
			(at 0 0 270)
			(layer "F.Fab")
			(effects
				(font
					(size 1.27 1.27)
				)
			)
		)
		(duplicate_pad_numbers_are_jumpers no)
		(fp_line
			(start -0.7874 0.4064)
			(end -0.7874 -0.4064)
			(stroke
				(width 0.1524)
				(type default)
			)
			(layer "F.SilkS")
		)
		(fp_line
			(start 0.7874 0.4064)
			(end -0.7874 0.4064)
			(stroke
				(width 0.1524)
				(type default)
			)
			(layer "F.SilkS")
		)
		(fp_line
			(start -0.7874 -0.4064)
			(end 0.7874 -0.4064)
			(stroke
				(width 0.1524)
				(type default)
			)
			(layer "F.SilkS")
		)
		(fp_line
			(start 0.7874 -0.4064)
			(end 0.7874 0.4064)
			(stroke
				(width 0.1524)
				(type default)
			)
			(layer "F.SilkS")
		)
		(fp_line
			(start -0.67945 0.3048)
			(end -0.67945 -0.305054)
			(stroke
				(width 0.1)
				(type default)
			)
			(layer "F.Fab")
		)
		(fp_line
			(start -0.12065 0.3048)
			(end -0.67945 0.3048)
			(stroke
				(width 0.1)
				(type default)
			)
			(layer "F.Fab")
		)
		(fp_line
			(start 0.120396 0.3048)
			(end 0.120396 0.2794)
			(stroke
				(width 0.1)
				(type default)
			)
			(layer "F.Fab")
		)
		(fp_line
			(start 0.67945 0.3048)
			(end 0.120396 0.3048)
			(stroke
				(width 0.1)
				(type default)
			)
			(layer "F.Fab")
		)
		(fp_line
			(start -0.12065 0.2794)
			(end -0.12065 0.3048)
			(stroke
				(width 0.1)
				(type default)
			)
			(layer "F.Fab")
		)
		(fp_line
			(start 0.120396 0.2794)
			(end -0.12065 0.2794)
			(stroke
				(width 0.1)
				(type default)
			)
			(layer "F.Fab")
		)
		(fp_line
			(start -0.12065 -0.2794)
			(end 0.12065 -0.2794)
			(stroke
				(width 0.1)
				(type default)
			)
			(layer "F.Fab")
		)
		(fp_line
			(start 0.12065 -0.2794)
			(end 0.12065 -0.3048)
			(stroke
				(width 0.1)
				(type default)
			)
			(layer "F.Fab")
		)
		(fp_line
			(start 0.12065 -0.3048)
			(end 0.67945 -0.3048)
			(stroke
				(width 0.1)
				(type default)
			)
			(layer "F.Fab")
		)
		(fp_line
			(start 0.67945 -0.3048)
			(end 0.67945 0.3048)
			(stroke
				(width 0.1)
				(type default)
			)
			(layer "F.Fab")
		)
		(fp_line
			(start -0.67945 -0.305054)
			(end -0.12065 -0.305054)
			(stroke
				(width 0.1)
				(type default)
			)
			(layer "F.Fab")
		)
		(fp_line
			(start -0.12065 -0.305054)
			(end -0.12065 -0.2794)
			(stroke
				(width 0.1)
				(type default)
			)
			(layer "F.Fab")
		)
		(pad "1" smd circle
			(at -0.40005 0 270)
			(size 0 0)
			(layers "F.Cu" "F.Mask" "F.Paste")
			(net "P12V_SCM_ADC_ALERT_R")
		)
		(pad "2" smd circle
			(at 0.40005 0 270)
			(size 0 0)
			(layers "F.Cu" "F.Mask" "F.Paste")
			(net "P12V_SCM_ADC_ALERT")
		)
	)
	(footprint ""
		(layer "F.Cu")
		(at 179.939442 -26.240232)
		(property "Reference" "PC2241"
			(at 0 0 0)
			(layer "F.SilkS")
			(hide yes)
			(effects
				(font
					(size 1.27 1.27)
				)
			)
		)
		(property "Value" ""
			(at 0 0 0)
			(layer "F.Fab")
			(effects
				(font
					(size 1.27 1.27)
				)
			)
		)
		(duplicate_pad_numbers_are_jumpers no)
		(fp_line
			(start -0.7874 -0.4064)
			(end 0.7874 -0.4064)
			(stroke
				(width 0.1524)
				(type default)
			)
			(layer "F.SilkS")
		)
		(fp_line
			(start -0.7874 0.4064)
			(end -0.7874 -0.4064)
			(stroke
				(width 0.1524)
				(type default)
			)
			(layer "F.SilkS")
		)
		(fp_line
			(start 0.7874 -0.4064)
			(end 0.7874 0.4064)
			(stroke
				(width 0.1524)
				(type default)
			)
			(layer "F.SilkS")
		)
		(fp_line
			(start 0.7874 0.4064)
			(end -0.7874 0.4064)
			(stroke
				(width 0.1524)
				(type default)
			)
			(layer "F.SilkS")
		)
		(fp_line
			(start -0.67945 -0.305054)
			(end -0.12065 -0.305054)
			(stroke
				(width 0.1)
				(type default)
			)
			(layer "F.Fab")
		)
		(fp_line
			(start -0.67945 0.3048)
			(end -0.67945 -0.305054)
			(stroke
				(width 0.1)
				(type default)
			)
			(layer "F.Fab")
		)
		(fp_line
			(start -0.12065 -0.305054)
			(end -0.12065 -0.2794)
			(stroke
				(width 0.1)
				(type default)
			)
			(layer "F.Fab")
		)
		(fp_line
			(start -0.12065 -0.2794)
			(end 0.12065 -0.2794)
			(stroke
				(width 0.1)
				(type default)
			)
			(layer "F.Fab")
		)
		(fp_line
			(start -0.12065 0.2794)
			(end -0.12065 0.3048)
			(stroke
				(width 0.1)
				(type default)
			)
			(layer "F.Fab")
		)
		(fp_line
			(start -0.12065 0.3048)
			(end -0.67945 0.3048)
			(stroke
				(width 0.1)
				(type default)
			)
			(layer "F.Fab")
		)
		(fp_line
			(start 0.120396 0.2794)
			(end -0.12065 0.2794)
			(stroke
				(width 0.1)
				(type default)
			)
			(layer "F.Fab")
		)
		(fp_line
			(start 0.120396 0.3048)
			(end 0.120396 0.2794)
			(stroke
				(width 0.1)
				(type default)
			)
			(layer "F.Fab")
		)
		(fp_line
			(start 0.12065 -0.3048)
			(end 0.67945 -0.3048)
			(stroke
				(width 0.1)
				(type default)
			)
			(layer "F.Fab")
		)
		(fp_line
			(start 0.12065 -0.2794)
			(end 0.12065 -0.3048)
			(stroke
				(width 0.1)
				(type default)
			)
			(layer "F.Fab")
		)
		(fp_line
			(start 0.67945 -0.3048)
			(end 0.67945 0.3048)
			(stroke
				(width 0.1)
				(type default)
			)
			(layer "F.Fab")
		)
		(fp_line
			(start 0.67945 0.3048)
			(end 0.120396 0.3048)
			(stroke
				(width 0.1)
				(type default)
			)
			(layer "F.Fab")
		)
		(pad "1" smd circle
			(at -0.40005 0)
			(size 0 0)
			(layers "F.Cu" "F.Mask" "F.Paste")
			(net "P12V_SCM_R")
		)
		(pad "2" smd circle
			(at 0.40005 0)
			(size 0 0)
			(layers "F.Cu" "F.Mask" "F.Paste")
			(net "GND")
		)
	)
	(footprint ""
		(layer "F.Cu")
		(at 54.902354 -375.49963 -90)
		(property "Reference" "C823"
			(at 0 0 270)
			(layer "F.SilkS")
			(hide yes)
			(effects
				(font
					(size 1.27 1.27)
				)
			)
		)
		(property "Value" ""
			(at 0 0 270)
			(layer "F.Fab")
			(effects
				(font
					(size 1.27 1.27)
				)
			)
		)
		(duplicate_pad_numbers_are_jumpers no)
		(fp_line
			(start -0.299974 0.150114)
			(end -0.299974 -0.150114)
			(stroke
				(width 0.1)
				(type default)
			)
			(layer "F.Fab")
		)
		(fp_line
			(start 0.299974 0.150114)
			(end -0.299974 0.150114)
			(stroke
				(width 0.1)
				(type default)
			)
			(layer "F.Fab")
		)
		(fp_line
			(start -0.299974 -0.150114)
			(end 0.299974 -0.150114)
			(stroke
				(width 0.1)
				(type default)
			)
			(layer "F.Fab")
		)
		(fp_line
			(start 0.299974 -0.150114)
			(end 0.299974 0.150114)
			(stroke
				(width 0.1)
				(type default)
			)
			(layer "F.Fab")
		)
		(pad "1" smd rect
			(at -0.2667 0 270)
			(size 0.3048 0.381)
			(layers "F.Cu" "F.Mask" "F.Paste")
			(net "P5E_CPU1_P0_TX_C_DP<7>")
		)
		(pad "2" smd rect
			(at 0.2667 0 270)
			(size 0.3048 0.381)
			(layers "F.Cu" "F.Mask" "F.Paste")
			(net "P5E_CPU1_P0_TX_DP<7>")
		)
	)
)
